FILE_TYPE = CONNECTIVITY;
{Allegro Design Entry HDL 17.2-2016 S081 (4005846) 1/11/2022}
"PAGE_NUMBER" = 131;
0"NC";
END.
